(kicad_pcb
	(version 20260206)
	(generator "pcbnew")
	(generator_version "10.0")
	(general
		(thickness 1.6)
		(legacy_teardrops no)
	)
	(paper "A4")
	(title_block
		(title "Wiwynn_Tioga_Pass_MB.brd")
		(comment 1 "Tioga Pass / footprint 2254 of 4770 (U5D1), pads 521-626 of 3647")
	)
	(layers
		(0 "F.Cu" signal "TOP")
		(4 "In1.Cu" signal "L2GND")
		(6 "In2.Cu" signal "L3")
		(8 "In3.Cu" signal "L4GND")
		(10 "In4.Cu" signal "L5")
		(12 "In5.Cu" signal "L6GND")
		(14 "In6.Cu" signal "L7VCC")
		(16 "In7.Cu" signal "L8VCC")
		(18 "In8.Cu" signal "L9GND")
		(20 "In9.Cu" signal "L10")
		(22 "In10.Cu" signal "L11GND")
		(24 "In11.Cu" signal "L12")
		(26 "In12.Cu" signal "L13GND")
		(2 "B.Cu" signal "BOTTOM")
		(9 "F.Adhes" user "F.Adhesive")
		(11 "B.Adhes" user "B.Adhesive")
		(13 "F.Paste" user "Package Geometry/Pastemask Top")
		(15 "B.Paste" user "Package Geometry/Pastemask Bottom")
		(5 "F.SilkS" user "Ref Des/Silkscreen Top")
		(7 "B.SilkS" user "Ref Des/Silkscreen Bottom")
		(1 "F.Mask" user "Board Geometry/Soldermask Top")
		(3 "B.Mask" user "Board Geometry/Soldermask Bottom")
		(17 "Dwgs.User" user "User.Drawings")
		(19 "Cmts.User" user "User.Comments")
		(21 "Eco1.User" user "User.Eco1")
		(23 "Eco2.User" user "User.Eco2")
		(25 "Edge.Cuts" user "Board Geometry/Outline")
		(27 "Margin" user)
		(31 "F.CrtYd" user "Package Geometry/Place Bound Top")
		(29 "B.CrtYd" user "Package Geometry/Place Bound Bottom")
		(35 "F.Fab" user "Ref Des/Assembly Top")
		(33 "B.Fab" user "Ref Des/Assembly Bottom")
	)
	(footprint ""
		(layer "F.Cu")
		(at 270.000222 -76.550012 180)
		(property "Reference" "U5D1"
			(at 19.124422 31.601918 0)
			(unlocked yes)
			(layer "F.SilkS")
			(effects
				(font
					(size 0.7874 0.5842)
					(thickness 0.1524)
				)
			)
		)
		(property "Value" ""
			(at 0 0 180)
			(layer "F.Fab")
			(effects
				(font
					(size 1.27 1.27)
				)
			)
		)
		(duplicate_pad_numbers_are_jumpers no)
		(pad "AN80" smd circle
			(at 32.099504 -11.053572)
			(size 0.4318 0.4318)
			(layers "F.Cu" "F.Mask" "F.Paste")
			(net "M_B_DQ<7>")
		)
		(pad "AN82" smd circle
			(at 33.816544 -11.053572)
			(size 0.4318 0.4318)
			(layers "F.Cu" "F.Mask" "F.Paste")
			(net "M_B_DQ<2>")
		)
		(pad "AN84" smd circle
			(at 35.533584 -11.053572)
			(size 0.4318 0.4318)
			(layers "F.Cu" "F.Mask" "F.Paste")
			(net "M_A_DQ<1>")
		)
		(pad "AN86" smd custom
			(at 37.250624 -11.053572 270)
			(size 0.10795 0.10795)
			(layers "F.Cu" "F.Mask" "F.Paste")
			(net "M_A_DQ<0>")
			(options
				(clearance outline)
				(anchor circle)
			)
			(primitives
				(gr_poly
					(pts
						(arc
							(start 0.2159 -0.0381)
							(mid 0 -0.254)
							(end -0.2159 -0.0381)
						)
						(arc
							(start -0.2159 0.0381)
							(mid 0 0.254)
							(end 0.2159 0.0381)
						)
					)
					(width 0)
					(fill yes)
				)
			)
		)
		(pad "AP1" smd custom
			(at -37.250624 -8.758428 90)
			(size 0.10795 0.10795)
			(layers "F.Cu" "F.Mask" "F.Paste")
			(net "UPI_CPU0_CPU1_P0P0_DP<7>")
			(options
				(clearance outline)
				(anchor circle)
			)
			(primitives
				(gr_poly
					(pts
						(arc
							(start 0.2159 -0.0381)
							(mid 0 -0.254)
							(end -0.2159 -0.0381)
						)
						(arc
							(start -0.2159 0.0381)
							(mid 0 0.254)
							(end 0.2159 0.0381)
						)
					)
					(width 0)
					(fill yes)
				)
			)
		)
		(pad "AP3" smd circle
			(at -35.533584 -8.758428)
			(size 0.4318 0.4318)
			(layers "F.Cu" "F.Mask" "F.Paste")
			(net "UPI_CPU0_CPU1_P0P0_DP<8>")
		)
		(pad "AP5" smd circle
			(at -33.816544 -8.758428)
			(size 0.4318 0.4318)
			(layers "F.Cu" "F.Mask" "F.Paste")
			(net "GND")
		)
		(pad "AP7" smd circle
			(at -32.099504 -8.758428)
			(size 0.4318 0.4318)
			(layers "F.Cu" "F.Mask" "F.Paste")
			(net "UPI_CPU1_CPU0_P0P0_DN<9>")
		)
		(pad "AP9" smd circle
			(at -30.382464 -8.758428)
			(size 0.4318 0.4318)
			(layers "F.Cu" "F.Mask" "F.Paste")
			(net "GND")
		)
		(pad "AP11" smd circle
			(at -28.665424 -8.758428)
			(size 0.4318 0.4318)
			(layers "F.Cu" "F.Mask" "F.Paste")
			(net "TP_NMI_CPU0")
		)
		(pad "AP13" smd circle
			(at -26.948384 -8.758428)
			(size 0.4318 0.4318)
			(layers "F.Cu" "F.Mask" "F.Paste")
			(net "GND")
		)
		(pad "AP17" smd circle
			(at -23.514558 -8.758428)
			(size 0.4318 0.4318)
			(layers "F.Cu" "F.Mask" "F.Paste")
			(net "XDP_CPU_PWR_DEBUG_N")
		)
		(pad "AP19" smd circle
			(at -21.797518 -8.758428)
			(size 0.4318 0.4318)
			(layers "F.Cu" "F.Mask" "F.Paste")
			(net "GND")
		)
		(pad "AP21" smd circle
			(at -20.080478 -8.758428)
			(size 0.4318 0.4318)
			(layers "F.Cu" "F.Mask" "F.Paste")
			(net "RST_CPU0_G_N")
		)
		(pad "AP23" smd circle
			(at -18.363438 -8.758428)
			(size 0.4318 0.4318)
			(layers "F.Cu" "F.Mask" "F.Paste")
			(net "PVCCMCP_CPU0")
		)
		(pad "AP25" smd circle
			(at -16.646398 -8.758428)
			(size 0.4318 0.4318)
			(layers "F.Cu" "F.Mask" "F.Paste")
			(net "PVCCMCP_CPU0")
		)
		(pad "AP27" smd circle
			(at -14.929612 -8.758428)
			(size 0.4318 0.4318)
			(layers "F.Cu" "F.Mask" "F.Paste")
			(net "CLK_100M_CPU0_RC_REFCLK0_DN")
		)
		(pad "AP29" smd circle
			(at -13.212572 -8.758428)
			(size 0.4318 0.4318)
			(layers "F.Cu" "F.Mask" "F.Paste")
			(net "A_CPU0_UPI01_RBIAS")
		)
		(pad "AP31" smd circle
			(at -11.495532 -8.758428)
			(size 0.4318 0.4318)
			(layers "F.Cu" "F.Mask" "F.Paste")
			(net "GND")
		)
		(pad "AP55" smd circle
			(at 10.637012 -10.558526)
			(size 0.508 0.508)
			(layers "F.Cu" "F.Mask" "F.Paste")
			(net "PVCCIN_CPU0")
		)
		(pad "AP57" smd circle
			(at 12.354052 -10.558526)
			(size 0.4318 0.4318)
			(layers "F.Cu" "F.Mask" "F.Paste")
			(net "PVCCIN_CPU0")
		)
		(pad "AP59" smd circle
			(at 14.071092 -10.558526)
			(size 0.4318 0.4318)
			(layers "F.Cu" "F.Mask" "F.Paste")
			(net "GND")
		)
		(pad "AP61" smd circle
			(at 15.787878 -10.558526)
			(size 0.4318 0.4318)
			(layers "F.Cu" "F.Mask" "F.Paste")
			(net "TP_CPU0_RSVD_194")
		)
		(pad "AP63" smd circle
			(at 17.504918 -10.558526)
			(size 0.4318 0.4318)
			(layers "F.Cu" "F.Mask" "F.Paste")
			(net "GND")
		)
		(pad "AP65" smd circle
			(at 19.221958 -10.558526)
			(size 0.4318 0.4318)
			(layers "F.Cu" "F.Mask" "F.Paste")
			(net "GND")
		)
		(pad "AP67" smd circle
			(at 20.938998 -10.558526)
			(size 0.4318 0.4318)
			(layers "F.Cu" "F.Mask" "F.Paste")
			(net "GND")
		)
		(pad "AP69" smd circle
			(at 22.656038 -10.558526)
			(size 0.4318 0.4318)
			(layers "F.Cu" "F.Mask" "F.Paste")
			(net "GND")
		)
		(pad "AP73" smd circle
			(at 26.090118 -10.558526)
			(size 0.4318 0.4318)
			(layers "F.Cu" "F.Mask" "F.Paste")
			(net "GND")
		)
		(pad "AP75" smd circle
			(at 27.806904 -10.558526)
			(size 0.4318 0.4318)
			(layers "F.Cu" "F.Mask" "F.Paste")
			(net "GND")
		)
		(pad "AP77" smd circle
			(at 29.523944 -10.558526)
			(size 0.4318 0.4318)
			(layers "F.Cu" "F.Mask" "F.Paste")
			(net "M_C_DQS_DN<9>")
		)
		(pad "AP79" smd circle
			(at 31.240984 -10.558526)
			(size 0.4318 0.4318)
			(layers "F.Cu" "F.Mask" "F.Paste")
			(net "M_B_DQS_DN<0>")
		)
		(pad "AP81" smd circle
			(at 32.958024 -10.558526)
			(size 0.4318 0.4318)
			(layers "F.Cu" "F.Mask" "F.Paste")
			(net "GND")
		)
		(pad "AP83" smd circle
			(at 34.675064 -10.558526)
			(size 0.4318 0.4318)
			(layers "F.Cu" "F.Mask" "F.Paste")
			(net "GND")
		)
		(pad "AP85" smd circle
			(at 36.392104 -10.558526)
			(size 0.4318 0.4318)
			(layers "F.Cu" "F.Mask" "F.Paste")
			(net "GND")
		)
		(pad "AR2" smd circle
			(at -36.392104 -8.262874)
			(size 0.4318 0.4318)
			(layers "F.Cu" "F.Mask" "F.Paste")
			(net "UPI_CPU0_CPU1_P0P0_DP<6>")
		)
		(pad "AR4" smd circle
			(at -34.675064 -8.262874)
			(size 0.4318 0.4318)
			(layers "F.Cu" "F.Mask" "F.Paste")
			(net "UPI_CPU0_CPU1_P0P0_DP<5>")
		)
		(pad "AR6" smd circle
			(at -32.958024 -8.262874)
			(size 0.4318 0.4318)
			(layers "F.Cu" "F.Mask" "F.Paste")
			(net "GND")
		)
		(pad "AR8" smd circle
			(at -31.240984 -8.262874)
			(size 0.4318 0.4318)
			(layers "F.Cu" "F.Mask" "F.Paste")
			(net "UPI_CPU1_CPU0_P0P0_DN<8>")
		)
		(pad "AR10" smd circle
			(at -29.523944 -8.262874)
			(size 0.4318 0.4318)
			(layers "F.Cu" "F.Mask" "F.Paste")
			(net "GND")
		)
		(pad "AR12" smd circle
			(at -27.806904 -8.262874)
			(size 0.4318 0.4318)
			(layers "F.Cu" "F.Mask" "F.Paste")
			(net "XDP_CPU_PREQ_N")
		)
		(pad "AR14" smd circle
			(at -26.090118 -8.262874)
			(size 0.4318 0.4318)
			(layers "F.Cu" "F.Mask" "F.Paste")
			(net "H_PM_SYNC_GTL_R1")
		)
		(pad "AR16" smd circle
			(at -24.373078 -8.262874)
			(size 0.4318 0.4318)
			(layers "F.Cu" "F.Mask" "F.Paste")
			(net "TP_CPU0_TEST_6")
		)
		(pad "AR18" smd circle
			(at -22.656038 -8.262874)
			(size 0.4318 0.4318)
			(layers "F.Cu" "F.Mask" "F.Paste")
			(net "PU_CPU0_SAFE_MODE_BOOT")
		)
		(pad "AR20" smd circle
			(at -20.938998 -8.262874)
			(size 0.4318 0.4318)
			(layers "F.Cu" "F.Mask" "F.Paste")
			(net "PVCCMCP_CPU0")
		)
		(pad "AR22" smd circle
			(at -19.221958 -8.262874)
			(size 0.4318 0.4318)
			(layers "F.Cu" "F.Mask" "F.Paste")
			(net "PVCCMCP_CPU0")
		)
		(pad "AR24" smd circle
			(at -17.504918 -8.262874)
			(size 0.4318 0.4318)
			(layers "F.Cu" "F.Mask" "F.Paste")
			(net "GND")
		)
		(pad "AR26" smd circle
			(at -15.787878 -8.262874)
			(size 0.4318 0.4318)
			(layers "F.Cu" "F.Mask" "F.Paste")
			(net "PVCCMCP_CPU0")
		)
		(pad "AR28" smd circle
			(at -14.071092 -8.262874)
			(size 0.4318 0.4318)
			(layers "F.Cu" "F.Mask" "F.Paste")
			(net "PVCCIO_CPU0")
		)
		(pad "AR30" smd circle
			(at -12.354052 -8.262874)
			(size 0.4318 0.4318)
			(layers "F.Cu" "F.Mask" "F.Paste")
			(net "GND")
		)
		(pad "AR56" smd circle
			(at 11.495532 -10.062972)
			(size 0.508 0.508)
			(layers "F.Cu" "F.Mask" "F.Paste")
			(net "PVCCIN_CPU0")
		)
		(pad "AR58" smd circle
			(at 13.212572 -10.062972)
			(size 0.4318 0.4318)
			(layers "F.Cu" "F.Mask" "F.Paste")
			(net "PVCCIN_CPU0")
		)
		(pad "AR60" smd circle
			(at 14.929612 -10.062972)
			(size 0.4318 0.4318)
			(layers "F.Cu" "F.Mask" "F.Paste")
			(net "GND")
		)
		(pad "AR62" smd circle
			(at 16.646398 -10.062972)
			(size 0.4318 0.4318)
			(layers "F.Cu" "F.Mask" "F.Paste")
			(net "TP_CPU0_RSVD_190")
		)
		(pad "AR64" smd circle
			(at 18.363438 -10.062972)
			(size 0.4318 0.4318)
			(layers "F.Cu" "F.Mask" "F.Paste")
			(net "M_C_DQ<27>")
		)
		(pad "AR66" smd circle
			(at 20.080478 -10.062972)
			(size 0.4318 0.4318)
			(layers "F.Cu" "F.Mask" "F.Paste")
			(net "M_C_DQS_DP<3>")
		)
		(pad "AR68" smd circle
			(at 21.797518 -10.062972)
			(size 0.4318 0.4318)
			(layers "F.Cu" "F.Mask" "F.Paste")
			(net "M_C_DQ<29>")
		)
		(pad "AR72" smd circle
			(at 25.231598 -10.062972)
			(size 0.4318 0.4318)
			(layers "F.Cu" "F.Mask" "F.Paste")
			(net "GND")
		)
		(pad "AR74" smd circle
			(at 26.948384 -10.062972)
			(size 0.4318 0.4318)
			(layers "F.Cu" "F.Mask" "F.Paste")
			(net "M_C_DQ<5>")
		)
		(pad "AR76" smd circle
			(at 28.665424 -10.062972)
			(size 0.4318 0.4318)
			(layers "F.Cu" "F.Mask" "F.Paste")
			(net "M_C_DQ<0>")
		)
		(pad "AR78" smd circle
			(at 30.382464 -10.062972)
			(size 0.4318 0.4318)
			(layers "F.Cu" "F.Mask" "F.Paste")
			(net "GND")
		)
		(pad "AR80" smd circle
			(at 32.099504 -10.062972)
			(size 0.4318 0.4318)
			(layers "F.Cu" "F.Mask" "F.Paste")
			(net "M_B_DQS_DP<0>")
		)
		(pad "AR82" smd circle
			(at 33.816544 -10.062972)
			(size 0.4318 0.4318)
			(layers "F.Cu" "F.Mask" "F.Paste")
			(net "M_B_DQ<6>")
		)
		(pad "AR84" smd circle
			(at 35.533584 -10.062972)
			(size 0.4318 0.4318)
			(layers "F.Cu" "F.Mask" "F.Paste")
			(net "M_A_DQ<5>")
		)
		(pad "AR86" smd custom
			(at 37.250624 -10.062972 270)
			(size 0.10795 0.10795)
			(layers "F.Cu" "F.Mask" "F.Paste")
			(net "M_A_DQ<4>")
			(options
				(clearance outline)
				(anchor circle)
			)
			(primitives
				(gr_poly
					(pts
						(arc
							(start 0.2159 -0.0381)
							(mid 0 -0.254)
							(end -0.2159 -0.0381)
						)
						(arc
							(start -0.2159 0.0381)
							(mid 0 0.254)
							(end 0.2159 0.0381)
						)
					)
					(width 0)
					(fill yes)
				)
			)
		)
		(pad "AT1" smd custom
			(at -37.250624 -7.767828 90)
			(size 0.10795 0.10795)
			(layers "F.Cu" "F.Mask" "F.Paste")
			(net "UPI_CPU0_CPU1_P0P0_DN<7>")
			(options
				(clearance outline)
				(anchor circle)
			)
			(primitives
				(gr_poly
					(pts
						(arc
							(start 0.2159 -0.0381)
							(mid 0 -0.254)
							(end -0.2159 -0.0381)
						)
						(arc
							(start -0.2159 0.0381)
							(mid 0 0.254)
							(end 0.2159 0.0381)
						)
					)
					(width 0)
					(fill yes)
				)
			)
		)
		(pad "AT3" smd circle
			(at -35.533584 -7.767828)
			(size 0.4318 0.4318)
			(layers "F.Cu" "F.Mask" "F.Paste")
			(net "UPI_CPU0_CPU1_P0P0_DN<6>")
		)
		(pad "AT5" smd circle
			(at -33.816544 -7.767828)
			(size 0.4318 0.4318)
			(layers "F.Cu" "F.Mask" "F.Paste")
			(net "PVCCIO_CPU0")
		)
		(pad "AT7" smd circle
			(at -32.099504 -7.767828)
			(size 0.4318 0.4318)
			(layers "F.Cu" "F.Mask" "F.Paste")
			(net "PVCCIO_CPU0")
		)
		(pad "AT9" smd circle
			(at -30.382464 -7.767828)
			(size 0.4318 0.4318)
			(layers "F.Cu" "F.Mask" "F.Paste")
			(net "UPI_CPU1_CPU0_P0P0_DP<7>")
		)
		(pad "AT11" smd circle
			(at -28.665424 -7.767828)
			(size 0.4318 0.4318)
			(layers "F.Cu" "F.Mask" "F.Paste")
			(net "PVCCIO_CPU0")
		)
		(pad "AT13" smd circle
			(at -26.948384 -7.767828)
			(size 0.4318 0.4318)
			(layers "F.Cu" "F.Mask" "F.Paste")
			(net "TP_CPU0_RSVD_189")
		)
		(pad "AT15" smd circle
			(at -25.231598 -7.767828)
			(size 0.4318 0.4318)
			(layers "F.Cu" "F.Mask" "F.Paste")
			(net "GND")
		)
		(pad "AT17" smd circle
			(at -23.514558 -7.767828)
			(size 0.4318 0.4318)
			(layers "F.Cu" "F.Mask" "F.Paste")
			(net "GND")
		)
		(pad "AT19" smd circle
			(at -21.797518 -7.767828)
			(size 0.4318 0.4318)
			(layers "F.Cu" "F.Mask" "F.Paste")
			(net "H_PMSYNC_CLK_24M_CPU0")
		)
		(pad "AT21" smd circle
			(at -20.080478 -7.767828)
			(size 0.4318 0.4318)
			(layers "F.Cu" "F.Mask" "F.Paste")
			(net "GND")
		)
		(pad "AT23" smd circle
			(at -18.363438 -7.767828)
			(size 0.4318 0.4318)
			(layers "F.Cu" "F.Mask" "F.Paste")
			(net "PVCCMCP_CPU0")
		)
		(pad "AT25" smd circle
			(at -16.646398 -7.767828)
			(size 0.4318 0.4318)
			(layers "F.Cu" "F.Mask" "F.Paste")
			(net "PVCCMCP_CPU0")
		)
		(pad "AT27" smd circle
			(at -14.929612 -7.767828)
			(size 0.4318 0.4318)
			(layers "F.Cu" "F.Mask" "F.Paste")
			(net "GND")
		)
		(pad "AT29" smd circle
			(at -13.212572 -7.767828)
			(size 0.4318 0.4318)
			(layers "F.Cu" "F.Mask" "F.Paste")
			(net "A_CPU0_UPI01_RBIAS")
		)
		(pad "AT57" smd circle
			(at 12.354052 -9.567926)
			(size 0.508 0.508)
			(layers "F.Cu" "F.Mask" "F.Paste")
			(net "PVCCIN_CPU0")
		)
		(pad "AT59" smd circle
			(at 14.071092 -9.567926)
			(size 0.4318 0.4318)
			(layers "F.Cu" "F.Mask" "F.Paste")
			(net "PVCCIN_CPU0")
		)
		(pad "AT61" smd circle
			(at 15.787878 -9.567926)
			(size 0.4318 0.4318)
			(layers "F.Cu" "F.Mask" "F.Paste")
			(net "GND")
		)
		(pad "AT63" smd circle
			(at 17.504918 -9.567926)
			(size 0.4318 0.4318)
			(layers "F.Cu" "F.Mask" "F.Paste")
			(net "GND")
		)
		(pad "AT65" smd circle
			(at 19.221958 -9.567926)
			(size 0.4318 0.4318)
			(layers "F.Cu" "F.Mask" "F.Paste")
			(net "M_C_DQ<31>")
		)
		(pad "AT67" smd circle
			(at 20.938998 -9.567926)
			(size 0.4318 0.4318)
			(layers "F.Cu" "F.Mask" "F.Paste")
			(net "M_C_DQ<25>")
		)
		(pad "AT69" smd circle
			(at 22.656038 -9.567926)
			(size 0.4318 0.4318)
			(layers "F.Cu" "F.Mask" "F.Paste")
			(net "GND")
		)
		(pad "AT71" smd circle
			(at 24.373078 -9.567926)
			(size 0.4318 0.4318)
			(layers "F.Cu" "F.Mask" "F.Paste")
			(net "M_C_DQS_DN<17>")
		)
		(pad "AT73" smd circle
			(at 26.090118 -9.567926)
			(size 0.4318 0.4318)
			(layers "F.Cu" "F.Mask" "F.Paste")
			(net "GND")
		)
		(pad "AT75" smd circle
			(at 27.806904 -9.567926)
			(size 0.4318 0.4318)
			(layers "F.Cu" "F.Mask" "F.Paste")
			(net "M_C_DQ<4>")
		)
		(pad "AT77" smd circle
			(at 29.523944 -9.567926)
			(size 0.4318 0.4318)
			(layers "F.Cu" "F.Mask" "F.Paste")
			(net "GND")
		)
		(pad "AT79" smd circle
			(at 31.240984 -9.567926)
			(size 0.4318 0.4318)
			(layers "F.Cu" "F.Mask" "F.Paste")
			(net "M_B_DQ<1>")
		)
		(pad "AT81" smd circle
			(at 32.958024 -9.567926)
			(size 0.4318 0.4318)
			(layers "F.Cu" "F.Mask" "F.Paste")
			(net "M_B_DQS_DP<9>")
		)
		(pad "AT83" smd circle
			(at 34.675064 -9.567926)
			(size 0.4318 0.4318)
			(layers "F.Cu" "F.Mask" "F.Paste")
			(net "GND")
		)
		(pad "AT85" smd circle
			(at 36.392104 -9.567926)
			(size 0.4318 0.4318)
			(layers "F.Cu" "F.Mask" "F.Paste")
			(net "GND")
		)
		(pad "AU2" smd circle
			(at -36.392104 -7.272274)
			(size 0.4318 0.4318)
			(layers "F.Cu" "F.Mask" "F.Paste")
			(net "GND")
		)
		(pad "AU4" smd circle
			(at -34.675064 -7.272274)
			(size 0.4318 0.4318)
			(layers "F.Cu" "F.Mask" "F.Paste")
			(net "UPI_CPU0_CPU1_P0P0_DN<5>")
		)
		(pad "AU6" smd circle
			(at -32.958024 -7.272274)
			(size 0.4318 0.4318)
			(layers "F.Cu" "F.Mask" "F.Paste")
			(net "GND")
		)
		(pad "AU8" smd circle
			(at -31.240984 -7.272274)
			(size 0.4318 0.4318)
			(layers "F.Cu" "F.Mask" "F.Paste")
			(net "UPI_CPU1_CPU0_P0P0_DP<8>")
		)
		(pad "AU10" smd circle
			(at -29.523944 -7.272274)
			(size 0.4318 0.4318)
			(layers "F.Cu" "F.Mask" "F.Paste")
			(net "UPI_CPU1_CPU0_P0P0_DN<7>")
		)
		(pad "AU12" smd circle
			(at -27.806904 -7.272274)
			(size 0.4318 0.4318)
			(layers "F.Cu" "F.Mask" "F.Paste")
			(net "PECI_CPU_G")
		)
		(pad "AU14" smd circle
			(at -26.090118 -7.272274)
			(size 0.4318 0.4318)
			(layers "F.Cu" "F.Mask" "F.Paste")
			(net "H_CPU0_FIVR_FAULT_G")
		)
		(pad "AU16" smd circle
			(at -24.373078 -7.272274)
			(size 0.4318 0.4318)
			(layers "F.Cu" "F.Mask" "F.Paste")
			(net "PU_CPU0_SOCKET_ID_1")
		)
		(pad "AU18" smd circle
			(at -22.656038 -7.272274)
			(size 0.4318 0.4318)
			(layers "F.Cu" "F.Mask" "F.Paste")
			(net "TP_CPU0_TEST_7")
		)
		(pad "AU20" smd circle
			(at -20.938998 -7.272274)
			(size 0.4318 0.4318)
			(layers "F.Cu" "F.Mask" "F.Paste")
			(net "TP_CPU0_SOCKET_ID_2")
		)
		(pad "AU22" smd circle
			(at -19.221958 -7.272274)
			(size 0.4318 0.4318)
			(layers "F.Cu" "F.Mask" "F.Paste")
			(net "PU_CPU0_SOCKET_ID_0")
		)
		(pad "AU24" smd circle
			(at -17.504918 -7.272274)
			(size 0.4318 0.4318)
			(layers "F.Cu" "F.Mask" "F.Paste")
			(net "CLK_100M_CPU0_BCLK0_DN")
		)
	)
)
